(kicad_pcb
	(version 20260206)
	(generator "pcbnew")
	(generator_version "10.0")
	(general
		(thickness 1.6)
		(legacy_teardrops no)
	)
	(paper "A4")
	(title_block
		(title "01162023_DA0F0TEBIF0_F0T_Expander_BD_F_brd_V02_OCP.brd")
		(comment 1 "Grand Teton / footprint 4457 of 9728 (J26), pads 110-179 of 179")
	)
	(layers
		(0 "F.Cu" signal "TOP")
		(4 "In1.Cu" signal "GND")
		(6 "In2.Cu" signal "VCC")
		(8 "In3.Cu" signal "VCC1")
		(10 "In4.Cu" signal "GND1")
		(12 "In5.Cu" signal "IN1")
		(14 "In6.Cu" signal "GND2")
		(16 "In7.Cu" signal "IN2")
		(18 "In8.Cu" signal "GND3")
		(20 "In9.Cu" signal "IN3")
		(22 "In10.Cu" signal "GND4")
		(24 "In11.Cu" signal "IN4")
		(26 "In12.Cu" signal "GND5")
		(28 "In13.Cu" signal "IN5")
		(30 "In14.Cu" signal "GND6")
		(32 "In15.Cu" signal "IN6")
		(34 "In16.Cu" signal "GND7")
		(2 "B.Cu" signal "BOTTOM")
		(9 "F.Adhes" user "F.Adhesive")
		(11 "B.Adhes" user "B.Adhesive")
		(13 "F.Paste" user "Package Geometry/Pastemask Top")
		(15 "B.Paste" user "Package Geometry/Pastemask Bottom")
		(5 "F.SilkS" user "Ref Des/Silkscreen Top")
		(7 "B.SilkS" user "Ref Des/Silkscreen Bottom")
		(1 "F.Mask" user "Board Geometry/Soldermask Top")
		(3 "B.Mask" user "Board Geometry/Soldermask Bottom")
		(17 "Dwgs.User" user "User.Drawings")
		(19 "Cmts.User" user "User.Comments")
		(21 "Eco1.User" user "User.Eco1")
		(23 "Eco2.User" user "User.Eco2")
		(25 "Edge.Cuts" user "Board Geometry/Outline")
		(27 "Margin" user)
		(31 "F.CrtYd" user "Package Geometry/Place Bound Top")
		(29 "B.CrtYd" user "Package Geometry/Place Bound Bottom")
		(35 "F.Fab" user "Ref Des/Assembly Top")
		(33 "B.Fab" user "Ref Des/Assembly Bottom")
	)
	(footprint ""
		(layer "F.Cu")
		(at 395.619986 -127.700024)
		(property "Reference" "J26"
			(at -5.373116 34.736024 90)
			(unlocked yes)
			(layer "F.SilkS")
			(effects
				(font
					(size 0.7874 0.5842)
					(thickness 0.1524)
				)
				(justify left)
			)
		)
		(property "Value" ""
			(at 0 0 0)
			(layer "F.Fab")
			(effects
				(font
					(size 1.27 1.27)
				)
			)
		)
		(duplicate_pad_numbers_are_jumpers no)
		(pad "B38" smd rect
			(at -1.27762 7.14502 270)
			(size 0.3556 1.2192)
			(layers "F.Cu" "F.Mask" "F.Paste")
			(net "GND")
		)
		(pad "B39" smd rect
			(at -1.27762 7.744968 270)
			(size 0.3556 1.2192)
			(layers "F.Cu" "F.Mask" "F.Paste")
			(net "P5E_PEX3_STN1_TX_C_DN<24>")
		)
		(pad "B40" smd rect
			(at -1.27762 8.344916 270)
			(size 0.3556 1.2192)
			(layers "F.Cu" "F.Mask" "F.Paste")
			(net "P5E_PEX3_STN1_TX_C_DP<24>")
		)
		(pad "B41" smd rect
			(at -1.27762 8.945118 270)
			(size 0.3556 1.2192)
			(layers "F.Cu" "F.Mask" "F.Paste")
			(net "GND")
		)
		(pad "B42" smd rect
			(at -1.27762 9.545066 270)
			(size 0.3556 1.2192)
			(layers "F.Cu" "F.Mask" "F.Paste")
			(net "PRSNTB0_NIC6_N")
		)
		(pad "B43" smd rect
			(at -1.27762 14.454886 270)
			(size 0.3556 1.2192)
			(layers "F.Cu" "F.Mask" "F.Paste")
			(net "GND")
		)
		(pad "B44" smd rect
			(at -1.27762 15.055088 270)
			(size 0.3556 1.2192)
			(layers "F.Cu" "F.Mask" "F.Paste")
			(net "P5E_PEX3_STN1_TX_C_DP<23>")
		)
		(pad "B45" smd rect
			(at -1.27762 15.655036 270)
			(size 0.3556 1.2192)
			(layers "F.Cu" "F.Mask" "F.Paste")
			(net "P5E_PEX3_STN1_TX_C_DN<23>")
		)
		(pad "B46" smd rect
			(at -1.27762 16.254984 270)
			(size 0.3556 1.2192)
			(layers "F.Cu" "F.Mask" "F.Paste")
			(net "GND")
		)
		(pad "B47" smd rect
			(at -1.27762 16.854932 270)
			(size 0.3556 1.2192)
			(layers "F.Cu" "F.Mask" "F.Paste")
			(net "P5E_PEX3_STN1_TX_C_DN<22>")
		)
		(pad "B48" smd rect
			(at -1.27762 17.45488 270)
			(size 0.3556 1.2192)
			(layers "F.Cu" "F.Mask" "F.Paste")
			(net "P5E_PEX3_STN1_TX_C_DP<22>")
		)
		(pad "B49" smd rect
			(at -1.27762 18.055082 270)
			(size 0.3556 1.2192)
			(layers "F.Cu" "F.Mask" "F.Paste")
			(net "GND")
		)
		(pad "B50" smd rect
			(at -1.27762 18.65503 270)
			(size 0.3556 1.2192)
			(layers "F.Cu" "F.Mask" "F.Paste")
			(net "P5E_PEX3_STN1_TX_C_DP<21>")
		)
		(pad "B51" smd rect
			(at -1.27762 19.254978 270)
			(size 0.3556 1.2192)
			(layers "F.Cu" "F.Mask" "F.Paste")
			(net "P5E_PEX3_STN1_TX_C_DN<21>")
		)
		(pad "B52" smd rect
			(at -1.27762 19.854926 270)
			(size 0.3556 1.2192)
			(layers "F.Cu" "F.Mask" "F.Paste")
			(net "GND")
		)
		(pad "B53" smd rect
			(at -1.27762 20.455128 270)
			(size 0.3556 1.2192)
			(layers "F.Cu" "F.Mask" "F.Paste")
			(net "P5E_PEX3_STN1_TX_C_DN<20>")
		)
		(pad "B54" smd rect
			(at -1.27762 21.055076 270)
			(size 0.3556 1.2192)
			(layers "F.Cu" "F.Mask" "F.Paste")
			(net "P5E_PEX3_STN1_TX_C_DP<20>")
		)
		(pad "B55" smd rect
			(at -1.27762 21.655024 270)
			(size 0.3556 1.2192)
			(layers "F.Cu" "F.Mask" "F.Paste")
			(net "GND")
		)
		(pad "B56" smd rect
			(at -1.27762 22.254972 270)
			(size 0.3556 1.2192)
			(layers "F.Cu" "F.Mask" "F.Paste")
			(net "P5E_PEX3_STN1_TX_C_DP<19>")
		)
		(pad "B57" smd rect
			(at -1.27762 22.85492 270)
			(size 0.3556 1.2192)
			(layers "F.Cu" "F.Mask" "F.Paste")
			(net "P5E_PEX3_STN1_TX_C_DN<19>")
		)
		(pad "B58" smd rect
			(at -1.27762 23.455122 270)
			(size 0.3556 1.2192)
			(layers "F.Cu" "F.Mask" "F.Paste")
			(net "GND")
		)
		(pad "B59" smd rect
			(at -1.27762 24.05507 270)
			(size 0.3556 1.2192)
			(layers "F.Cu" "F.Mask" "F.Paste")
			(net "P5E_PEX3_STN1_TX_C_DN<18>")
		)
		(pad "B60" smd rect
			(at -1.27762 24.655018 270)
			(size 0.3556 1.2192)
			(layers "F.Cu" "F.Mask" "F.Paste")
			(net "P5E_PEX3_STN1_TX_C_DP<18>")
		)
		(pad "B61" smd rect
			(at -1.27762 25.254966 270)
			(size 0.3556 1.2192)
			(layers "F.Cu" "F.Mask" "F.Paste")
			(net "GND")
		)
		(pad "B62" smd rect
			(at -1.27762 25.854914 270)
			(size 0.3556 1.2192)
			(layers "F.Cu" "F.Mask" "F.Paste")
			(net "P5E_PEX3_STN1_TX_C_DP<17>")
		)
		(pad "B63" smd rect
			(at -1.27762 26.455116 270)
			(size 0.3556 1.2192)
			(layers "F.Cu" "F.Mask" "F.Paste")
			(net "P5E_PEX3_STN1_TX_C_DN<17>")
		)
		(pad "B64" smd rect
			(at -1.27762 27.055064 270)
			(size 0.3556 1.2192)
			(layers "F.Cu" "F.Mask" "F.Paste")
			(net "GND")
		)
		(pad "B65" smd rect
			(at -1.27762 27.655012 270)
			(size 0.3556 1.2192)
			(layers "F.Cu" "F.Mask" "F.Paste")
			(net "P5E_PEX3_STN1_TX_C_DN<16>")
		)
		(pad "B66" smd rect
			(at -1.27762 28.25496 270)
			(size 0.3556 1.2192)
			(layers "F.Cu" "F.Mask" "F.Paste")
			(net "P5E_PEX3_STN1_TX_C_DP<16>")
		)
		(pad "B67" smd rect
			(at -1.27762 28.854908 270)
			(size 0.3556 1.2192)
			(layers "F.Cu" "F.Mask" "F.Paste")
			(net "GND")
		)
		(pad "B68" smd rect
			(at -1.27762 29.45511 270)
			(size 0.3556 1.2192)
			(layers "F.Cu" "F.Mask" "F.Paste")
			(net "Net_2659")
		)
		(pad "B69" smd rect
			(at -1.27762 30.055058 270)
			(size 0.3556 1.2192)
			(layers "F.Cu" "F.Mask" "F.Paste")
			(net "Net_2660")
		)
		(pad "B70" smd rect
			(at -1.27762 30.655006 270)
			(size 0.3556 1.2192)
			(layers "F.Cu" "F.Mask" "F.Paste")
			(net "PRSNTB3_NIC6_N")
		)
		(pad "G1" thru_hole oval
			(at 1.022604 -34.034984 270)
			(size 1.6256 3.4798)
			(drill oval 1.1176 2.4638)
			(layers "*.Cu" "*.Mask")
			(remove_unused_layers no)
			(net "GND")
			(clearance 0.127)
			(thermal_gap 0.127)
		)
		(pad "G2" thru_hole oval
			(at 1.022604 -20.625054 270)
			(size 1.6256 3.4798)
			(drill oval 1.1176 2.4638)
			(layers "*.Cu" "*.Mask")
			(remove_unused_layers no)
			(net "GND")
			(clearance 0.127)
			(thermal_gap 0.127)
		)
		(pad "G3" thru_hole oval
			(at 1.022604 -0.255016 270)
			(size 1.6256 3.4798)
			(drill oval 1.1176 2.4638)
			(layers "*.Cu" "*.Mask")
			(remove_unused_layers no)
			(net "GND")
			(clearance 0.127)
			(thermal_gap 0.127)
		)
		(pad "G4" thru_hole oval
			(at 1.022604 12.005056 270)
			(size 1.6256 3.4798)
			(drill oval 1.1176 2.4638)
			(layers "*.Cu" "*.Mask")
			(remove_unused_layers no)
			(net "GND")
			(clearance 0.127)
			(thermal_gap 0.127)
		)
		(pad "G5" thru_hole oval
			(at 1.022604 34.034984 270)
			(size 1.5748 3.4798)
			(drill oval 1.1176 2.4638)
			(layers "*.Cu" "*.Mask")
			(remove_unused_layers no)
			(net "GND")
			(clearance 0.1524)
			(thermal_gap 0.1524)
		)
		(pad "G6" thru_hole circle
			(at -3.16738 -20.625054)
			(size 1.6256 1.6256)
			(drill 1.1176)
			(layers "*.Cu" "*.Mask")
			(remove_unused_layers no)
			(net "GND")
			(clearance 0)
		)
		(pad "G7" thru_hole circle
			(at -3.16738 12.005056)
			(size 1.6256 1.6256)
			(drill 1.1176)
			(layers "*.Cu" "*.Mask")
			(remove_unused_layers no)
			(net "GND")
			(clearance 0)
		)
		(pad "G8" thru_hole circle
			(at 4.20243 -20.625054)
			(size 1.6256 1.6256)
			(drill 1.1176)
			(layers "*.Cu" "*.Mask")
			(remove_unused_layers no)
			(net "GND")
			(clearance 0)
		)
		(pad "G9" thru_hole circle
			(at 4.20243 12.005056)
			(size 1.6256 1.6256)
			(drill 1.1176)
			(layers "*.Cu" "*.Mask")
			(remove_unused_layers no)
			(net "GND")
			(clearance 0)
		)
		(pad "OA1" smd rect
			(at 3.322574 -30.660086 270)
			(size 0.3556 1.2192)
			(layers "F.Cu" "F.Mask" "F.Paste")
			(net "RST_NIC6_PERST2_R_N")
		)
		(pad "OA2" smd rect
			(at 3.322574 -30.059884 270)
			(size 0.3556 1.2192)
			(layers "F.Cu" "F.Mask" "F.Paste")
			(net "RST_NIC6_PERST3_R_N")
		)
		(pad "OA3" smd rect
			(at 3.322574 -29.459936 270)
			(size 0.3556 1.2192)
			(layers "F.Cu" "F.Mask" "F.Paste")
			(net "Net_2663")
		)
		(pad "OA4" smd rect
			(at 3.322574 -28.859988 270)
			(size 0.3556 1.2192)
			(layers "F.Cu" "F.Mask" "F.Paste")
			(net "NIC6_RBT_ARB_IN")
		)
		(pad "OA5" smd rect
			(at 3.322574 -28.26004 270)
			(size 0.3556 1.2192)
			(layers "F.Cu" "F.Mask" "F.Paste")
			(net "NIC6_RBT_ARB_OUT")
		)
		(pad "OA6" smd rect
			(at 3.322574 -27.660092 270)
			(size 0.3556 1.2192)
			(layers "F.Cu" "F.Mask" "F.Paste")
			(net "NIC6_SLOT_ID1")
		)
		(pad "OA7" smd rect
			(at 3.322574 -27.05989 270)
			(size 0.3556 1.2192)
			(layers "F.Cu" "F.Mask" "F.Paste")
			(net "NCSI_NIC6_TX_EN")
		)
		(pad "OA8" smd rect
			(at 3.322574 -26.459942 270)
			(size 0.3556 1.2192)
			(layers "F.Cu" "F.Mask" "F.Paste")
			(net "NCSI_NIC6_TXD1")
		)
		(pad "OA9" smd rect
			(at 3.322574 -25.859994 270)
			(size 0.3556 1.2192)
			(layers "F.Cu" "F.Mask" "F.Paste")
			(net "NCSI_NIC6_TXD0")
		)
		(pad "OA10" smd rect
			(at 3.322574 -25.260046 270)
			(size 0.3556 1.2192)
			(layers "F.Cu" "F.Mask" "F.Paste")
			(net "GND")
		)
		(pad "OA11" smd rect
			(at 3.322574 -24.660098 270)
			(size 0.3556 1.2192)
			(layers "F.Cu" "F.Mask" "F.Paste")
			(net "Net_2655")
		)
		(pad "OA12" smd rect
			(at 3.322574 -24.059896 270)
			(size 0.3556 1.2192)
			(layers "F.Cu" "F.Mask" "F.Paste")
			(net "Net_2658")
		)
		(pad "OA13" smd rect
			(at 3.322574 -23.459948 270)
			(size 0.3556 1.2192)
			(layers "F.Cu" "F.Mask" "F.Paste")
			(net "GND")
		)
		(pad "OA14" smd rect
			(at 3.322574 -22.86 270)
			(size 0.3556 1.2192)
			(layers "F.Cu" "F.Mask" "F.Paste")
			(net "CLK_50M_NIC6_RBT_REF")
		)
		(pad "OB1" smd rect
			(at -1.27762 -30.660086 270)
			(size 0.3556 1.2192)
			(layers "F.Cu" "F.Mask" "F.Paste")
			(net "PWRGD_NIC6_PWR_GOOD")
		)
		(pad "OB2" smd rect
			(at -1.27762 -30.059884 270)
			(size 0.3556 1.2192)
			(layers "F.Cu" "F.Mask" "F.Paste")
			(net "NIC6_MAIN_PWR_EN_R")
		)
		(pad "OB3" smd rect
			(at -1.27762 -29.459936 270)
			(size 0.3556 1.2192)
			(layers "F.Cu" "F.Mask" "F.Paste")
			(net "NIC6_LD_N")
		)
		(pad "OB4" smd rect
			(at -1.27762 -28.859988 270)
			(size 0.3556 1.2192)
			(layers "F.Cu" "F.Mask" "F.Paste")
			(net "NIC6_DATA_IN")
		)
		(pad "OB5" smd rect
			(at -1.27762 -28.26004 270)
			(size 0.3556 1.2192)
			(layers "F.Cu" "F.Mask" "F.Paste")
			(net "NIC6_DATA_OUT")
		)
		(pad "OB6" smd rect
			(at -1.27762 -27.660092 270)
			(size 0.3556 1.2192)
			(layers "F.Cu" "F.Mask" "F.Paste")
			(net "NIC6_CLK")
		)
		(pad "OB7" smd rect
			(at -1.27762 -27.05989 270)
			(size 0.3556 1.2192)
			(layers "F.Cu" "F.Mask" "F.Paste")
			(net "NIC6_SLOT_ID0")
		)
		(pad "OB8" smd rect
			(at -1.27762 -26.459942 270)
			(size 0.3556 1.2192)
			(layers "F.Cu" "F.Mask" "F.Paste")
			(net "NCSI_NIC6_RXD1")
		)
		(pad "OB9" smd rect
			(at -1.27762 -25.859994 270)
			(size 0.3556 1.2192)
			(layers "F.Cu" "F.Mask" "F.Paste")
			(net "NCSI_NIC6_RXD0")
		)
		(pad "OB10" smd rect
			(at -1.27762 -25.260046 270)
			(size 0.3556 1.2192)
			(layers "F.Cu" "F.Mask" "F.Paste")
			(net "GND")
		)
		(pad "OB11" smd rect
			(at -1.27762 -24.660098 270)
			(size 0.3556 1.2192)
			(layers "F.Cu" "F.Mask" "F.Paste")
			(net "Net_2654")
		)
		(pad "OB12" smd rect
			(at -1.27762 -24.059896 270)
			(size 0.3556 1.2192)
			(layers "F.Cu" "F.Mask" "F.Paste")
			(net "Net_2657")
		)
		(pad "OB13" smd rect
			(at -1.27762 -23.459948 270)
			(size 0.3556 1.2192)
			(layers "F.Cu" "F.Mask" "F.Paste")
			(net "GND")
		)
		(pad "OB14" smd rect
			(at -1.27762 -22.86 270)
			(size 0.3556 1.2192)
			(layers "F.Cu" "F.Mask" "F.Paste")
			(net "NCSI_NIC6_CRS_DV")
		)
	)
)
